# BASEBOARD_FAB2 (Tioga Pass) — schematic netlist excerpt (pin names and nets, part order shuffled) for the footprints in the layout excerpt that follows; sources: Cadence DE-HDL packaged netlist, KiCad conversion of Wiwynn_Tioga_Pass_MB.brd

R9G31  RES  33.2 1% CHIP  pkg 0402  page 152 : A = H_CPU0_MEMDEF_MEMHOT_LVT3_K_N ; B = H_CPU0_MEMDEF_MEMHOT_LVT3_N
R2N21  RES  0.0 5% CHIP  pkg 0402  page 138 : A = SMB_LAN_STBY_LVC3_SCL_R2 ; B = SMB_LAN_STBY_LVC3_SCL
C9N22  CAP_A  22.0UF 4V 20% X6S  pkg 0603V  page 210 : A = PVSA_CPU1 ; B = GND

(kicad_pcb
	(version 20260206)
	(generator "pcbnew")
	(generator_version "10.0")
	(general
		(thickness 1.6)
		(legacy_teardrops no)
	)
	(paper "A4")
	(title_block
		(title "Wiwynn_Tioga_Pass_MB.brd")
		(comment 1 "Tioga Pass / footprints 4566-4568 of 4770")
	)
	(layers
		(0 "F.Cu" signal "TOP")
		(4 "In1.Cu" signal "L2GND")
		(6 "In2.Cu" signal "L3")
		(8 "In3.Cu" signal "L4GND")
		(10 "In4.Cu" signal "L5")
		(12 "In5.Cu" signal "L6GND")
		(14 "In6.Cu" signal "L7VCC")
		(16 "In7.Cu" signal "L8VCC")
		(18 "In8.Cu" signal "L9GND")
		(20 "In9.Cu" signal "L10")
		(22 "In10.Cu" signal "L11GND")
		(24 "In11.Cu" signal "L12")
		(26 "In12.Cu" signal "L13GND")
		(2 "B.Cu" signal "BOTTOM")
		(9 "F.Adhes" user "F.Adhesive")
		(11 "B.Adhes" user "B.Adhesive")
		(13 "F.Paste" user "Package Geometry/Pastemask Top")
		(15 "B.Paste" user "Package Geometry/Pastemask Bottom")
		(5 "F.SilkS" user "Ref Des/Silkscreen Top")
		(7 "B.SilkS" user "Ref Des/Silkscreen Bottom")
		(1 "F.Mask" user "Board Geometry/Soldermask Top")
		(3 "B.Mask" user "Board Geometry/Soldermask Bottom")
		(17 "Dwgs.User" user "User.Drawings")
		(19 "Cmts.User" user "User.Comments")
		(21 "Eco1.User" user "User.Eco1")
		(23 "Eco2.User" user "User.Eco2")
		(25 "Edge.Cuts" user "Board Geometry/Outline")
		(27 "Margin" user)
		(31 "F.CrtYd" user "Package Geometry/Place Bound Top")
		(29 "B.CrtYd" user "Package Geometry/Place Bound Bottom")
		(35 "F.Fab" user "Ref Des/Assembly Top")
		(33 "B.Fab" user "Ref Des/Assembly Bottom")
	)
	(footprint ""
		(layer "B.Cu")
		(at 428.279052 -13.794994 -90)
		(property "Reference" "R9G31"
			(at 0 0 90)
			(layer "B.SilkS")
			(hide yes)
			(effects
				(font
					(size 1.27 1.27)
				)
				(justify mirror)
			)
		)
		(property "Value" ""
			(at 0 0 90)
			(layer "B.Fab")
			(effects
				(font
					(size 1.27 1.27)
				)
				(justify mirror)
			)
		)
		(duplicate_pad_numbers_are_jumpers no)
		(fp_poly
			(pts
				(xy 0.2794 -0.1016) (xy -0.2794 -0.1016) (xy -0.2794 0.9906) (xy 0.2794 0.9906)
			)
			(stroke
				(width 0)
				(type default)
			)
			(fill no)
			(layer "B.CrtYd")
		)
		(fp_line
			(start -0.2794 0.9906)
			(end -0.2794 -0.1016)
			(stroke
				(width 0.1)
				(type default)
			)
			(layer "B.Fab")
		)
		(fp_line
			(start 0.2794 0.9906)
			(end -0.2794 0.9906)
			(stroke
				(width 0.1)
				(type default)
			)
			(layer "B.Fab")
		)
		(fp_line
			(start -0.2794 -0.1016)
			(end 0.2794 -0.1016)
			(stroke
				(width 0.1)
				(type default)
			)
			(layer "B.Fab")
		)
		(fp_line
			(start 0.2794 -0.1016)
			(end 0.2794 0.9906)
			(stroke
				(width 0.1)
				(type default)
			)
			(layer "B.Fab")
		)
		(pad "1" smd rect
			(at 0 0 90)
			(size 0.508 0.508)
			(layers "B.Cu" "B.Mask" "B.Paste")
			(net "H_CPU0_MEMDEF_MEMHOT_LVT3_K_N")
		)
		(pad "2" smd rect
			(at 0 0.889 90)
			(size 0.508 0.508)
			(layers "B.Cu" "B.Mask" "B.Paste")
			(net "H_CPU0_MEMDEF_MEMHOT_LVT3_N")
		)
		(zone
			(layer "B.Cu")
			(hatch none 0.5)
			(connect_pads
				(clearance 0)
			)
			(min_thickness 0.25)
			(keepout
				(tracks not_allowed)
				(vias allowed)
				(pads allowed)
				(copperpour not_allowed)
				(footprints allowed)
			)
			(placement
				(enabled no)
				(sheetname "")
			)
			(fill
				(thermal_gap 0.5)
				(thermal_bridge_width 0.5)
				(island_removal_mode 0)
			)
			(polygon
				(pts
					(xy 427.644052 -13.540994) (xy 427.644052 -14.048994) (xy 428.025052 -14.048994) (xy 428.025052 -13.540994)
				)
			)
		)
		(zone
			(layer "B.Cu")
			(hatch none 0.5)
			(connect_pads
				(clearance 0)
			)
			(min_thickness 0.25)
			(keepout
				(tracks allowed)
				(vias not_allowed)
				(pads allowed)
				(copperpour not_allowed)
				(footprints allowed)
			)
			(placement
				(enabled no)
				(sheetname "")
			)
			(fill
				(thermal_gap 0.5)
				(thermal_bridge_width 0.5)
				(island_removal_mode 0)
			)
			(polygon
				(pts
					(xy 428.025052 -13.540994) (xy 428.025052 -14.048994) (xy 427.644052 -14.048994) (xy 427.644052 -13.540994)
				)
			)
		)
	)
	(footprint ""
		(layer "B.Cu")
		(at 49.4284 -93.7514)
		(property "Reference" "C9N22"
			(at 0 0 0)
			(layer "B.SilkS")
			(hide yes)
			(effects
				(font
					(size 1.27 1.27)
				)
				(justify mirror)
			)
		)
		(property "Value" ""
			(at 0 0 0)
			(layer "B.Fab")
			(effects
				(font
					(size 1.27 1.27)
				)
				(justify mirror)
			)
		)
		(duplicate_pad_numbers_are_jumpers no)
		(fp_poly
			(pts
				(xy 0.4953 -0.2032) (xy -0.4953 -0.2032) (xy -0.4953 1.6002) (xy 0.4953 1.6002)
			)
			(stroke
				(width 0)
				(type default)
			)
			(fill no)
			(layer "B.CrtYd")
		)
		(fp_line
			(start -0.4953 -0.2032)
			(end -0.4953 1.6002)
			(stroke
				(width 0.1)
				(type default)
			)
			(layer "B.Fab")
		)
		(fp_line
			(start -0.4953 1.6002)
			(end 0.4953 1.6002)
			(stroke
				(width 0.1)
				(type default)
			)
			(layer "B.Fab")
		)
		(fp_line
			(start 0.4953 -0.2032)
			(end -0.4953 -0.2032)
			(stroke
				(width 0.1)
				(type default)
			)
			(layer "B.Fab")
		)
		(fp_line
			(start 0.4953 1.6002)
			(end 0.4953 -0.2032)
			(stroke
				(width 0.1)
				(type default)
			)
			(layer "B.Fab")
		)
		(pad "1" smd rect
			(at 0 0 180)
			(size 0.762 0.889)
			(layers "B.Cu" "B.Mask" "B.Paste")
			(net "PVSA_CPU1")
		)
		(pad "2" smd rect
			(at 0 1.397 180)
			(size 0.762 0.889)
			(layers "B.Cu" "B.Mask" "B.Paste")
			(net "GND")
		)
		(zone
			(layer "B.Cu")
			(hatch none 0.5)
			(connect_pads
				(clearance 0)
			)
			(min_thickness 0.25)
			(keepout
				(tracks not_allowed)
				(vias allowed)
				(pads allowed)
				(copperpour not_allowed)
				(footprints allowed)
			)
			(placement
				(enabled no)
				(sheetname "")
			)
			(fill
				(thermal_gap 0.5)
				(thermal_bridge_width 0.5)
				(island_removal_mode 0)
			)
			(polygon
				(pts
					(xy 49.8094 -93.3069) (xy 49.0474 -93.3069) (xy 49.0474 -92.7989) (xy 49.8094 -92.7989)
				)
			)
		)
	)
	(footprint ""
		(layer "B.Cu")
		(at 395.351 -88.2015)
		(property "Reference" "R2N21"
			(at 0 0 0)
			(layer "B.SilkS")
			(hide yes)
			(effects
				(font
					(size 1.27 1.27)
				)
				(justify mirror)
			)
		)
		(property "Value" ""
			(at 0 0 0)
			(layer "B.Fab")
			(effects
				(font
					(size 1.27 1.27)
				)
				(justify mirror)
			)
		)
		(duplicate_pad_numbers_are_jumpers no)
		(fp_poly
			(pts
				(xy 0.2794 -0.1016) (xy -0.2794 -0.1016) (xy -0.2794 0.9906) (xy 0.2794 0.9906)
			)
			(stroke
				(width 0)
				(type default)
			)
			(fill no)
			(layer "B.CrtYd")
		)
		(fp_line
			(start -0.2794 -0.1016)
			(end 0.2794 -0.1016)
			(stroke
				(width 0.1)
				(type default)
			)
			(layer "B.Fab")
		)
		(fp_line
			(start -0.2794 0.9906)
			(end -0.2794 -0.1016)
			(stroke
				(width 0.1)
				(type default)
			)
			(layer "B.Fab")
		)
		(fp_line
			(start 0.2794 -0.1016)
			(end 0.2794 0.9906)
			(stroke
				(width 0.1)
				(type default)
			)
			(layer "B.Fab")
		)
		(fp_line
			(start 0.2794 0.9906)
			(end -0.2794 0.9906)
			(stroke
				(width 0.1)
				(type default)
			)
			(layer "B.Fab")
		)
		(pad "1" smd rect
			(at 0 0 180)
			(size 0.508 0.508)
			(layers "B.Cu" "B.Mask" "B.Paste")
			(net "SMB_LAN_STBY_LVC3_SCL_R2")
		)
		(pad "2" smd rect
			(at 0 0.889 180)
			(size 0.508 0.508)
			(layers "B.Cu" "B.Mask" "B.Paste")
			(net "SMB_LAN_STBY_LVC3_SCL")
		)
		(zone
			(layer "B.Cu")
			(hatch none 0.5)
			(connect_pads
				(clearance 0)
			)
			(min_thickness 0.25)
			(keepout
				(tracks allowed)
				(vias not_allowed)
				(pads allowed)
				(copperpour not_allowed)
				(footprints allowed)
			)
			(placement
				(enabled no)
				(sheetname "")
			)
			(fill
				(thermal_gap 0.5)
				(thermal_bridge_width 0.5)
				(island_removal_mode 0)
			)
			(polygon
				(pts
					(xy 395.605 -87.9475) (xy 395.097 -87.9475) (xy 395.097 -87.5665) (xy 395.605 -87.5665)
				)
			)
		)
		(zone
			(layer "B.Cu")
			(hatch none 0.5)
			(connect_pads
				(clearance 0)
			)
			(min_thickness 0.25)
			(keepout
				(tracks not_allowed)
				(vias allowed)
				(pads allowed)
				(copperpour not_allowed)
				(footprints allowed)
			)
			(placement
				(enabled no)
				(sheetname "")
			)
			(fill
				(thermal_gap 0.5)
				(thermal_bridge_width 0.5)
				(island_removal_mode 0)
			)
			(polygon
				(pts
					(xy 395.605 -87.5665) (xy 395.097 -87.5665) (xy 395.097 -87.9475) (xy 395.605 -87.9475)
				)
			)
		)
	)
)
